(kicad_pcb
	(version 20260206)
	(generator "pcbnew")
	(generator_version "10.0")
	(general
		(thickness 1.6)
		(legacy_teardrops no)
	)
	(paper "A4")
	(title_block
		(title "fcb — Lightning_FCB_BRD.brd")
		(comment 1 "Lightning (Wiwynn / Facebook NVMe JBOF) / footprints 350-356 of 495")
	)
	(layers
		(0 "F.Cu" signal "TOP")
		(4 "In1.Cu" signal "L2GND")
		(6 "In2.Cu" signal "L3VCC")
		(2 "B.Cu" signal "BOTTOM")
		(9 "F.Adhes" user "F.Adhesive")
		(11 "B.Adhes" user "B.Adhesive")
		(13 "F.Paste" user "Package Geometry/Pastemask Top")
		(15 "B.Paste" user "Package Geometry/Pastemask Bottom")
		(5 "F.SilkS" user "Ref Des/Silkscreen Top")
		(7 "B.SilkS" user "Ref Des/Silkscreen Bottom")
		(1 "F.Mask" user "Board Geometry/Soldermask Top")
		(3 "B.Mask" user "Board Geometry/Soldermask Bottom")
		(17 "Dwgs.User" user "User.Drawings")
		(19 "Cmts.User" user "User.Comments")
		(21 "Eco1.User" user "User.Eco1")
		(23 "Eco2.User" user "User.Eco2")
		(25 "Edge.Cuts" user "Board Geometry/Outline")
		(27 "Margin" user)
		(31 "F.CrtYd" user "Package Geometry/Place Bound Top")
		(29 "B.CrtYd" user "Package Geometry/Place Bound Bottom")
		(35 "F.Fab" user "Ref Des/Assembly Top")
		(33 "B.Fab" user "Ref Des/Assembly Bottom")
	)
	(footprint ""
		(layer "F.Cu")
		(at 7.8232 -81.6102 90)
		(property "Reference" "R29"
			(at 0 0 90)
			(layer "F.SilkS")
			(hide yes)
			(effects
				(font
					(size 1.27 1.27)
				)
			)
		)
		(property "Value" "33R2F-3-GP"
			(at 0.064008 -3.993896 90)
			(unlocked yes)
			(layer "F.Fab")
			(hide yes)
			(effects
				(font
					(size 1.016 1.016)
					(thickness 0.1524)
				)
			)
		)
		(property "Device Type" "R402H16"
			(at 0.064008 -5.517896 90)
			(unlocked yes)
			(layer "F.Fab")
			(hide yes)
			(effects
				(font
					(size 1.016 1.016)
					(thickness 0.1524)
				)
			)
		)
		(duplicate_pad_numbers_are_jumpers no)
		(fp_line
			(start 0.508 -0.9398)
			(end -0.508 -0.9398)
			(stroke
				(width 0.1524)
				(type default)
			)
			(layer "F.SilkS")
		)
		(fp_line
			(start -0.508 -0.9398)
			(end -0.508 0.9398)
			(stroke
				(width 0.1524)
				(type default)
			)
			(layer "F.SilkS")
		)
		(fp_rect
			(start -0.508 0.9398)
			(end 0.508 -0.9398)
			(stroke
				(width 0)
				(type default)
			)
			(fill no)
			(layer "F.CrtYd")
		)
		(fp_rect
			(start -0.508 0.9398)
			(end 0.508 -0.9398)
			(stroke
				(width 0)
				(type default)
			)
			(fill no)
			(layer "F.Fab")
		)
		(pad "1" smd custom
			(at 0 -0.4445 90)
			(size 0.1397 0.1397)
			(layers "F.Cu" "F.Mask" "F.Paste")
			(net "P3V3")
			(options
				(clearance outline)
				(anchor circle)
			)
			(primitives
				(gr_poly
					(pts
						(arc
							(start -0.1778 -0.2794)
							(mid -0.249642 -0.249642)
							(end -0.2794 -0.1778)
						)
						(arc
							(start -0.2794 0.1778)
							(mid -0.249642 0.249642)
							(end -0.1778 0.2794)
						)
						(arc
							(start 0.1778 0.2794)
							(mid 0.249642 0.249642)
							(end 0.2794 0.1778)
						)
						(arc
							(start 0.2794 -0.1778)
							(mid 0.249642 -0.249642)
							(end 0.1778 -0.2794)
						)
					)
					(width 0)
					(fill yes)
				)
			)
		)
		(pad "2" smd custom
			(at 0 0.4445 90)
			(size 0.1397 0.1397)
			(layers "F.Cu" "F.Mask" "F.Paste")
			(net "LED_DR_LED4_BLUE")
			(options
				(clearance outline)
				(anchor circle)
			)
			(primitives
				(gr_poly
					(pts
						(arc
							(start -0.1778 -0.2794)
							(mid -0.249642 -0.249642)
							(end -0.2794 -0.1778)
						)
						(arc
							(start -0.2794 0.1778)
							(mid -0.249642 0.249642)
							(end -0.1778 0.2794)
						)
						(arc
							(start 0.1778 0.2794)
							(mid 0.249642 0.249642)
							(end 0.2794 0.1778)
						)
						(arc
							(start 0.2794 -0.1778)
							(mid 0.249642 -0.249642)
							(end 0.1778 -0.2794)
						)
					)
					(width 0)
					(fill yes)
				)
			)
		)
	)
	(footprint ""
		(layer "F.Cu")
		(at 8.3058 -64.8208)
		(property "Reference" "R25"
			(at 0 0 0)
			(layer "F.SilkS")
			(hide yes)
			(effects
				(font
					(size 1.27 1.27)
				)
			)
		)
		(property "Value" "33R2F-3-GP"
			(at 0.064008 -3.993896 0)
			(unlocked yes)
			(layer "F.Fab")
			(hide yes)
			(effects
				(font
					(size 1.016 1.016)
					(thickness 0.1524)
				)
			)
		)
		(property "Device Type" "R402H16"
			(at 0.064008 -5.517896 0)
			(unlocked yes)
			(layer "F.Fab")
			(hide yes)
			(effects
				(font
					(size 1.016 1.016)
					(thickness 0.1524)
				)
			)
		)
		(duplicate_pad_numbers_are_jumpers no)
		(fp_line
			(start -0.508 -0.9398)
			(end -0.508 0.9398)
			(stroke
				(width 0.1524)
				(type default)
			)
			(layer "F.SilkS")
		)
		(fp_line
			(start 0.508 -0.9398)
			(end -0.508 -0.9398)
			(stroke
				(width 0.1524)
				(type default)
			)
			(layer "F.SilkS")
		)
		(fp_rect
			(start -0.508 0.9398)
			(end 0.508 -0.9398)
			(stroke
				(width 0)
				(type default)
			)
			(fill no)
			(layer "F.CrtYd")
		)
		(fp_rect
			(start -0.508 0.9398)
			(end 0.508 -0.9398)
			(stroke
				(width 0)
				(type default)
			)
			(fill no)
			(layer "F.Fab")
		)
		(pad "1" smd custom
			(at 0 -0.4445)
			(size 0.1397 0.1397)
			(layers "F.Cu" "F.Mask" "F.Paste")
			(net "P3V3")
			(options
				(clearance outline)
				(anchor circle)
			)
			(primitives
				(gr_poly
					(pts
						(arc
							(start -0.1778 -0.2794)
							(mid -0.249642 -0.249642)
							(end -0.2794 -0.1778)
						)
						(arc
							(start -0.2794 0.1778)
							(mid -0.249642 0.249642)
							(end -0.1778 0.2794)
						)
						(arc
							(start 0.1778 0.2794)
							(mid 0.249642 0.249642)
							(end 0.2794 0.1778)
						)
						(arc
							(start 0.2794 -0.1778)
							(mid 0.249642 -0.249642)
							(end 0.1778 -0.2794)
						)
					)
					(width 0)
					(fill yes)
				)
			)
		)
		(pad "2" smd custom
			(at 0 0.4445)
			(size 0.1397 0.1397)
			(layers "F.Cu" "F.Mask" "F.Paste")
			(net "LED_DR_LED5_BLUE")
			(options
				(clearance outline)
				(anchor circle)
			)
			(primitives
				(gr_poly
					(pts
						(arc
							(start -0.1778 -0.2794)
							(mid -0.249642 -0.249642)
							(end -0.2794 -0.1778)
						)
						(arc
							(start -0.2794 0.1778)
							(mid -0.249642 0.249642)
							(end -0.1778 0.2794)
						)
						(arc
							(start 0.1778 0.2794)
							(mid 0.249642 0.249642)
							(end 0.2794 0.1778)
						)
						(arc
							(start 0.2794 -0.1778)
							(mid 0.249642 -0.249642)
							(end 0.1778 -0.2794)
						)
					)
					(width 0)
					(fill yes)
				)
			)
		)
	)
	(footprint ""
		(layer "F.Cu")
		(at 39.064184 -360.4768 90)
		(property "Reference" "PR59"
			(at 0 0 90)
			(layer "F.SilkS")
			(hide yes)
			(effects
				(font
					(size 1.27 1.27)
				)
			)
		)
		(property "Value" "4K7R2F-GP"
			(at 0.064008 -3.993896 90)
			(unlocked yes)
			(layer "F.Fab")
			(hide yes)
			(effects
				(font
					(size 1.016 1.016)
					(thickness 0.1524)
				)
			)
		)
		(property "Device Type" "R402H16"
			(at 0.064008 -5.517896 90)
			(unlocked yes)
			(layer "F.Fab")
			(hide yes)
			(effects
				(font
					(size 1.016 1.016)
					(thickness 0.1524)
				)
			)
		)
		(duplicate_pad_numbers_are_jumpers no)
		(fp_line
			(start 0.508 -0.9398)
			(end -0.508 -0.9398)
			(stroke
				(width 0.1524)
				(type default)
			)
			(layer "F.SilkS")
		)
		(fp_line
			(start -0.508 -0.9398)
			(end -0.508 0.9398)
			(stroke
				(width 0.1524)
				(type default)
			)
			(layer "F.SilkS")
		)
		(fp_rect
			(start -0.508 0.9398)
			(end 0.508 -0.9398)
			(stroke
				(width 0)
				(type default)
			)
			(fill no)
			(layer "F.CrtYd")
		)
		(fp_rect
			(start -0.508 0.9398)
			(end 0.508 -0.9398)
			(stroke
				(width 0)
				(type default)
			)
			(fill no)
			(layer "F.Fab")
		)
		(pad "1" smd custom
			(at 0 -0.4445 90)
			(size 0.1397 0.1397)
			(layers "F.Cu" "F.Mask" "F.Paste")
			(net "P12V_AUX")
			(options
				(clearance outline)
				(anchor circle)
			)
			(primitives
				(gr_poly
					(pts
						(arc
							(start -0.1778 -0.2794)
							(mid -0.249642 -0.249642)
							(end -0.2794 -0.1778)
						)
						(arc
							(start -0.2794 0.1778)
							(mid -0.249642 0.249642)
							(end -0.1778 0.2794)
						)
						(arc
							(start 0.1778 0.2794)
							(mid 0.249642 0.249642)
							(end 0.2794 0.1778)
						)
						(arc
							(start 0.2794 -0.1778)
							(mid 0.249642 -0.249642)
							(end 0.1778 -0.2794)
						)
					)
					(width 0)
					(fill yes)
				)
			)
		)
		(pad "2" smd custom
			(at 0 0.4445 90)
			(size 0.1397 0.1397)
			(layers "F.Cu" "F.Mask" "F.Paste")
			(net "OTP_RETRY_B")
			(options
				(clearance outline)
				(anchor circle)
			)
			(primitives
				(gr_poly
					(pts
						(arc
							(start -0.1778 -0.2794)
							(mid -0.249642 -0.249642)
							(end -0.2794 -0.1778)
						)
						(arc
							(start -0.2794 0.1778)
							(mid -0.249642 0.249642)
							(end -0.1778 0.2794)
						)
						(arc
							(start 0.1778 0.2794)
							(mid 0.249642 0.249642)
							(end 0.2794 0.1778)
						)
						(arc
							(start 0.2794 -0.1778)
							(mid 0.249642 -0.249642)
							(end 0.1778 -0.2794)
						)
					)
					(width 0)
					(fill yes)
				)
			)
		)
	)
	(footprint ""
		(layer "F.Cu")
		(at 5.4864 -449.4784 -90)
		(property "Reference" "R104"
			(at 0 0 270)
			(layer "F.SilkS")
			(hide yes)
			(effects
				(font
					(size 1.27 1.27)
				)
			)
		)
		(property "Value" "10KR2F-2-GP"
			(at 0.064008 -3.993896 270)
			(unlocked yes)
			(layer "F.Fab")
			(hide yes)
			(effects
				(font
					(size 1.016 1.016)
					(thickness 0.1524)
				)
			)
		)
		(property "Device Type" "R402H16"
			(at 0.064008 -5.517896 270)
			(unlocked yes)
			(layer "F.Fab")
			(hide yes)
			(effects
				(font
					(size 1.016 1.016)
					(thickness 0.1524)
				)
			)
		)
		(duplicate_pad_numbers_are_jumpers no)
		(fp_line
			(start -0.508 -0.9398)
			(end -0.508 0.9398)
			(stroke
				(width 0.1524)
				(type default)
			)
			(layer "F.SilkS")
		)
		(fp_line
			(start 0.508 -0.9398)
			(end -0.508 -0.9398)
			(stroke
				(width 0.1524)
				(type default)
			)
			(layer "F.SilkS")
		)
		(fp_rect
			(start -0.508 0.9398)
			(end 0.508 -0.9398)
			(stroke
				(width 0)
				(type default)
			)
			(fill no)
			(layer "F.CrtYd")
		)
		(fp_rect
			(start -0.508 0.9398)
			(end 0.508 -0.9398)
			(stroke
				(width 0)
				(type default)
			)
			(fill no)
			(layer "F.Fab")
		)
		(pad "1" smd custom
			(at 0 -0.4445 270)
			(size 0.1397 0.1397)
			(layers "F.Cu" "F.Mask" "F.Paste")
			(net "FANIN_1")
			(options
				(clearance outline)
				(anchor circle)
			)
			(primitives
				(gr_poly
					(pts
						(arc
							(start -0.1778 -0.2794)
							(mid -0.249642 -0.249642)
							(end -0.2794 -0.1778)
						)
						(arc
							(start -0.2794 0.1778)
							(mid -0.249642 0.249642)
							(end -0.1778 0.2794)
						)
						(arc
							(start 0.1778 0.2794)
							(mid 0.249642 0.249642)
							(end 0.2794 0.1778)
						)
						(arc
							(start 0.2794 -0.1778)
							(mid 0.249642 -0.249642)
							(end 0.1778 -0.2794)
						)
					)
					(width 0)
					(fill yes)
				)
			)
		)
		(pad "2" smd custom
			(at 0 0.4445 270)
			(size 0.1397 0.1397)
			(layers "F.Cu" "F.Mask" "F.Paste")
			(net "GND")
			(options
				(clearance outline)
				(anchor circle)
			)
			(primitives
				(gr_poly
					(pts
						(arc
							(start -0.1778 -0.2794)
							(mid -0.249642 -0.249642)
							(end -0.2794 -0.1778)
						)
						(arc
							(start -0.2794 0.1778)
							(mid -0.249642 0.249642)
							(end -0.1778 0.2794)
						)
						(arc
							(start 0.1778 0.2794)
							(mid 0.249642 0.249642)
							(end 0.2794 0.1778)
						)
						(arc
							(start 0.2794 -0.1778)
							(mid 0.249642 -0.249642)
							(end 0.1778 -0.2794)
						)
					)
					(width 0)
					(fill yes)
				)
			)
		)
	)
	(footprint ""
		(layer "F.Cu")
		(at 34.99231 -167.734234)
		(property "Reference" "R9"
			(at 0 0 0)
			(layer "F.SilkS")
			(hide yes)
			(effects
				(font
					(size 1.27 1.27)
				)
			)
		)
		(property "Value" "100KR2J-1-GP"
			(at 0.064008 -3.993896 0)
			(unlocked yes)
			(layer "F.Fab")
			(hide yes)
			(effects
				(font
					(size 1.016 1.016)
					(thickness 0.1524)
				)
			)
		)
		(property "Device Type" "R402H16"
			(at 0.064008 -5.517896 0)
			(unlocked yes)
			(layer "F.Fab")
			(hide yes)
			(effects
				(font
					(size 1.016 1.016)
					(thickness 0.1524)
				)
			)
		)
		(duplicate_pad_numbers_are_jumpers no)
		(fp_line
			(start -0.508 -0.9398)
			(end -0.508 0.9398)
			(stroke
				(width 0.1524)
				(type default)
			)
			(layer "F.SilkS")
		)
		(fp_line
			(start 0.508 -0.9398)
			(end -0.508 -0.9398)
			(stroke
				(width 0.1524)
				(type default)
			)
			(layer "F.SilkS")
		)
		(fp_rect
			(start -0.508 0.9398)
			(end 0.508 -0.9398)
			(stroke
				(width 0)
				(type default)
			)
			(fill no)
			(layer "F.CrtYd")
		)
		(fp_rect
			(start -0.508 0.9398)
			(end 0.508 -0.9398)
			(stroke
				(width 0)
				(type default)
			)
			(fill no)
			(layer "F.Fab")
		)
		(pad "1" smd custom
			(at 0 -0.4445)
			(size 0.1397 0.1397)
			(layers "F.Cu" "F.Mask" "F.Paste")
			(net "P3V3")
			(options
				(clearance outline)
				(anchor circle)
			)
			(primitives
				(gr_poly
					(pts
						(arc
							(start -0.1778 -0.2794)
							(mid -0.249642 -0.249642)
							(end -0.2794 -0.1778)
						)
						(arc
							(start -0.2794 0.1778)
							(mid -0.249642 0.249642)
							(end -0.1778 0.2794)
						)
						(arc
							(start 0.1778 0.2794)
							(mid 0.249642 0.249642)
							(end 0.2794 0.1778)
						)
						(arc
							(start 0.2794 -0.1778)
							(mid 0.249642 -0.249642)
							(end 0.1778 -0.2794)
						)
					)
					(width 0)
					(fill yes)
				)
			)
		)
		(pad "2" smd custom
			(at 0 0.4445)
			(size 0.1397 0.1397)
			(layers "F.Cu" "F.Mask" "F.Paste")
			(net "NCT7904_ADR")
			(options
				(clearance outline)
				(anchor circle)
			)
			(primitives
				(gr_poly
					(pts
						(arc
							(start -0.1778 -0.2794)
							(mid -0.249642 -0.249642)
							(end -0.2794 -0.1778)
						)
						(arc
							(start -0.2794 0.1778)
							(mid -0.249642 0.249642)
							(end -0.1778 0.2794)
						)
						(arc
							(start 0.1778 0.2794)
							(mid 0.249642 0.249642)
							(end 0.2794 0.1778)
						)
						(arc
							(start 0.2794 -0.1778)
							(mid 0.249642 -0.249642)
							(end 0.1778 -0.2794)
						)
					)
					(width 0)
					(fill yes)
				)
			)
		)
	)
	(footprint ""
		(layer "F.Cu")
		(at 31.7246 -184.2516)
		(property "Reference" "PR117"
			(at 0 0 0)
			(layer "F.SilkS")
			(hide yes)
			(effects
				(font
					(size 1.27 1.27)
				)
			)
		)
		(property "Value" "3K3R3F-GP"
			(at -0.0254 -2.5146 0)
			(unlocked yes)
			(layer "F.Fab")
			(hide yes)
			(effects
				(font
					(size 1.016 1.016)
					(thickness 0.1524)
				)
			)
		)
		(property "Device Type" "R603H22"
			(at -0.0254 -4.0386 0)
			(unlocked yes)
			(layer "F.Fab")
			(hide yes)
			(effects
				(font
					(size 1.016 1.016)
					(thickness 0.1524)
				)
			)
		)
		(duplicate_pad_numbers_are_jumpers no)
		(fp_line
			(start -0.4826 0)
			(end -0.2032 0)
			(stroke
				(width 0.2032)
				(type default)
			)
			(layer "F.SilkS")
		)
		(fp_line
			(start 0.2032 0)
			(end 0.4826 0)
			(stroke
				(width 0.2032)
				(type default)
			)
			(layer "F.SilkS")
		)
		(fp_rect
			(start -0.5842 1.3335)
			(end 0.5842 -1.3335)
			(stroke
				(width 0)
				(type default)
			)
			(fill no)
			(layer "F.CrtYd")
		)
		(fp_rect
			(start -0.5842 1.3335)
			(end 0.5842 -1.3335)
			(stroke
				(width 0)
				(type default)
			)
			(fill no)
			(layer "F.Fab")
		)
		(pad "1" smd custom
			(at 0 -0.762)
			(size 0.2159 0.2159)
			(layers "F.Cu" "F.Mask" "F.Paste")
			(net "P12V_AUX")
			(options
				(clearance outline)
				(anchor circle)
			)
			(primitives
				(gr_poly
					(pts
						(arc
							(start -0.3302 -0.4318)
							(mid -0.402042 -0.402042)
							(end -0.4318 -0.3302)
						)
						(arc
							(start -0.4318 0.3302)
							(mid -0.402042 0.402042)
							(end -0.3302 0.4318)
						)
						(arc
							(start 0.3302 0.4318)
							(mid 0.402042 0.402042)
							(end 0.4318 0.3302)
						)
						(arc
							(start 0.4318 -0.3302)
							(mid 0.402042 -0.402042)
							(end 0.3302 -0.4318)
						)
					)
					(width 0)
					(fill yes)
				)
			)
		)
		(pad "2" smd custom
			(at 0 0.762)
			(size 0.2159 0.2159)
			(layers "F.Cu" "F.Mask" "F.Paste")
			(net "P3V3_AUX_BJT_B")
			(options
				(clearance outline)
				(anchor circle)
			)
			(primitives
				(gr_poly
					(pts
						(arc
							(start -0.3302 -0.4318)
							(mid -0.402042 -0.402042)
							(end -0.4318 -0.3302)
						)
						(arc
							(start -0.4318 0.3302)
							(mid -0.402042 0.402042)
							(end -0.3302 0.4318)
						)
						(arc
							(start 0.3302 0.4318)
							(mid 0.402042 0.402042)
							(end 0.4318 0.3302)
						)
						(arc
							(start 0.4318 -0.3302)
							(mid 0.402042 -0.402042)
							(end 0.3302 -0.4318)
						)
					)
					(width 0)
					(fill yes)
				)
			)
		)
	)
	(footprint ""
		(layer "F.Cu")
		(at 16.052292 -289.636962 180)
		(property "Reference" "R102"
			(at 0 0 180)
			(layer "F.SilkS")
			(hide yes)
			(effects
				(font
					(size 1.27 1.27)
				)
			)
		)
		(property "Value" "10KR2F-2-GP"
			(at 0.064008 -3.993896 180)
			(unlocked yes)
			(layer "F.Fab")
			(hide yes)
			(effects
				(font
					(size 1.016 1.016)
					(thickness 0.1524)
				)
			)
		)
		(property "Device Type" "R402H16"
			(at 0.064008 -5.517896 180)
			(unlocked yes)
			(layer "F.Fab")
			(hide yes)
			(effects
				(font
					(size 1.016 1.016)
					(thickness 0.1524)
				)
			)
		)
		(duplicate_pad_numbers_are_jumpers no)
		(fp_line
			(start 0.508 -0.9398)
			(end -0.508 -0.9398)
			(stroke
				(width 0.1524)
				(type default)
			)
			(layer "F.SilkS")
		)
		(fp_line
			(start -0.508 -0.9398)
			(end -0.508 0.9398)
			(stroke
				(width 0.1524)
				(type default)
			)
			(layer "F.SilkS")
		)
		(fp_rect
			(start -0.508 0.9398)
			(end 0.508 -0.9398)
			(stroke
				(width 0)
				(type default)
			)
			(fill no)
			(layer "F.CrtYd")
		)
		(fp_rect
			(start -0.508 0.9398)
			(end 0.508 -0.9398)
			(stroke
				(width 0)
				(type default)
			)
			(fill no)
			(layer "F.Fab")
		)
		(pad "1" smd custom
			(at 0 -0.4445 180)
			(size 0.1397 0.1397)
			(layers "F.Cu" "F.Mask" "F.Paste")
			(net "FANIN_3")
			(options
				(clearance outline)
				(anchor circle)
			)
			(primitives
				(gr_poly
					(pts
						(arc
							(start -0.1778 -0.2794)
							(mid -0.249642 -0.249642)
							(end -0.2794 -0.1778)
						)
						(arc
							(start -0.2794 0.1778)
							(mid -0.249642 0.249642)
							(end -0.1778 0.2794)
						)
						(arc
							(start 0.1778 0.2794)
							(mid 0.249642 0.249642)
							(end 0.2794 0.1778)
						)
						(arc
							(start 0.2794 -0.1778)
							(mid 0.249642 -0.249642)
							(end 0.1778 -0.2794)
						)
					)
					(width 0)
					(fill yes)
				)
			)
		)
		(pad "2" smd custom
			(at 0 0.4445 180)
			(size 0.1397 0.1397)
			(layers "F.Cu" "F.Mask" "F.Paste")
			(net "GND")
			(options
				(clearance outline)
				(anchor circle)
			)
			(primitives
				(gr_poly
					(pts
						(arc
							(start -0.1778 -0.2794)
							(mid -0.249642 -0.249642)
							(end -0.2794 -0.1778)
						)
						(arc
							(start -0.2794 0.1778)
							(mid -0.249642 0.249642)
							(end -0.1778 0.2794)
						)
						(arc
							(start 0.1778 0.2794)
							(mid 0.249642 0.249642)
							(end 0.2794 0.1778)
						)
						(arc
							(start 0.2794 -0.1778)
							(mid 0.249642 -0.249642)
							(end 0.1778 -0.2794)
						)
					)
					(width 0)
					(fill yes)
				)
			)
		)
	)
)
